# T6G (Grand Teton) — schematic netlist excerpt (pin names and nets, part order shuffled) for the footprints in the layout excerpt that follows; sources: Cadence DE-HDL packaged netlist, KiCad conversion of 04192023_DAF0TMB3IC0_F0TG_MB_C_brd_V02_OCP.brd

C6005  Q_CAP  0.1UF 25V 10% X7R  pkg 0402  page 113 : A = P2E_MB_BMC_TX_BUF2_DP<0> ; B = P2E_MB_BMC_TX_BUF_C_DP<0>
R8382  Q_RES  0 5% CHIP  pkg 0402LF  page 224 : A = SMB_SCM_2_R2_SDA ; B = PVDD11_S3_P1_PMSDA_R

(kicad_pcb
	(version 20260206)
	(generator "pcbnew")
	(generator_version "10.0")
	(general
		(thickness 1.6)
		(legacy_teardrops no)
	)
	(paper "A4")
	(title_block
		(title "04192023_DAF0TMB3IC0_F0TG_MB_C_brd_V02_OCP.brd")
		(comment 1 "Grand Teton / footprints 3705-3706 of 8354")
	)
	(layers
		(0 "F.Cu" signal "TOP")
		(4 "In1.Cu" signal "GND")
		(6 "In2.Cu" signal "IN1")
		(8 "In3.Cu" signal "GND1")
		(10 "In4.Cu" signal "IN2")
		(12 "In5.Cu" signal "GND2")
		(14 "In6.Cu" signal "IN3")
		(16 "In7.Cu" signal "GND3")
		(18 "In8.Cu" signal "VCC")
		(20 "In9.Cu" signal "VCC1")
		(22 "In10.Cu" signal "GND4")
		(24 "In11.Cu" signal "IN4")
		(26 "In12.Cu" signal "GND5")
		(28 "In13.Cu" signal "IN5")
		(30 "In14.Cu" signal "GND6")
		(32 "In15.Cu" signal "IN6")
		(34 "In16.Cu" signal "GND7")
		(2 "B.Cu" signal "BOTTOM")
		(9 "F.Adhes" user "F.Adhesive")
		(11 "B.Adhes" user "B.Adhesive")
		(13 "F.Paste" user "Package Geometry/Pastemask Top")
		(15 "B.Paste" user "Package Geometry/Pastemask Bottom")
		(5 "F.SilkS" user "Ref Des/Silkscreen Top")
		(7 "B.SilkS" user "Ref Des/Silkscreen Bottom")
		(1 "F.Mask" user "Board Geometry/Soldermask Top")
		(3 "B.Mask" user "Board Geometry/Soldermask Bottom")
		(17 "Dwgs.User" user "User.Drawings")
		(19 "Cmts.User" user "User.Comments")
		(21 "Eco1.User" user "User.Eco1")
		(23 "Eco2.User" user "User.Eco2")
		(25 "Edge.Cuts" user "Board Geometry/Outline")
		(27 "Margin" user)
		(31 "F.CrtYd" user "Package Geometry/Place Bound Top")
		(29 "B.CrtYd" user "Package Geometry/Place Bound Bottom")
		(35 "F.Fab" user "Ref Des/Assembly Top")
		(33 "B.Fab" user "Ref Des/Assembly Bottom")
	)
	(footprint ""
		(layer "F.Cu")
		(at 161.06013 -352.668078 -90)
		(property "Reference" "R8382"
			(at 0 0 270)
			(layer "F.SilkS")
			(hide yes)
			(effects
				(font
					(size 1.27 1.27)
				)
			)
		)
		(property "Value" ""
			(at 0 0 270)
			(layer "F.Fab")
			(effects
				(font
					(size 1.27 1.27)
				)
			)
		)
		(duplicate_pad_numbers_are_jumpers no)
		(fp_line
			(start -0.7874 0.4064)
			(end -0.7874 -0.4064)
			(stroke
				(width 0.1524)
				(type default)
			)
			(layer "F.SilkS")
		)
		(fp_line
			(start 0.7874 0.4064)
			(end -0.7874 0.4064)
			(stroke
				(width 0.1524)
				(type default)
			)
			(layer "F.SilkS")
		)
		(fp_line
			(start -0.7874 -0.4064)
			(end 0.7874 -0.4064)
			(stroke
				(width 0.1524)
				(type default)
			)
			(layer "F.SilkS")
		)
		(fp_line
			(start 0.7874 -0.4064)
			(end 0.7874 0.4064)
			(stroke
				(width 0.1524)
				(type default)
			)
			(layer "F.SilkS")
		)
		(fp_line
			(start -0.67945 0.3048)
			(end -0.67945 -0.305054)
			(stroke
				(width 0.1)
				(type default)
			)
			(layer "F.Fab")
		)
		(fp_line
			(start -0.12065 0.3048)
			(end -0.67945 0.3048)
			(stroke
				(width 0.1)
				(type default)
			)
			(layer "F.Fab")
		)
		(fp_line
			(start 0.120396 0.3048)
			(end 0.120396 0.2794)
			(stroke
				(width 0.1)
				(type default)
			)
			(layer "F.Fab")
		)
		(fp_line
			(start 0.67945 0.3048)
			(end 0.120396 0.3048)
			(stroke
				(width 0.1)
				(type default)
			)
			(layer "F.Fab")
		)
		(fp_line
			(start -0.12065 0.2794)
			(end -0.12065 0.3048)
			(stroke
				(width 0.1)
				(type default)
			)
			(layer "F.Fab")
		)
		(fp_line
			(start 0.120396 0.2794)
			(end -0.12065 0.2794)
			(stroke
				(width 0.1)
				(type default)
			)
			(layer "F.Fab")
		)
		(fp_line
			(start -0.12065 -0.2794)
			(end 0.12065 -0.2794)
			(stroke
				(width 0.1)
				(type default)
			)
			(layer "F.Fab")
		)
		(fp_line
			(start 0.12065 -0.2794)
			(end 0.12065 -0.3048)
			(stroke
				(width 0.1)
				(type default)
			)
			(layer "F.Fab")
		)
		(fp_line
			(start 0.12065 -0.3048)
			(end 0.67945 -0.3048)
			(stroke
				(width 0.1)
				(type default)
			)
			(layer "F.Fab")
		)
		(fp_line
			(start 0.67945 -0.3048)
			(end 0.67945 0.3048)
			(stroke
				(width 0.1)
				(type default)
			)
			(layer "F.Fab")
		)
		(fp_line
			(start -0.67945 -0.305054)
			(end -0.12065 -0.305054)
			(stroke
				(width 0.1)
				(type default)
			)
			(layer "F.Fab")
		)
		(fp_line
			(start -0.12065 -0.305054)
			(end -0.12065 -0.2794)
			(stroke
				(width 0.1)
				(type default)
			)
			(layer "F.Fab")
		)
		(pad "1" smd circle
			(at -0.40005 0 270)
			(size 0 0)
			(layers "F.Cu" "F.Mask" "F.Paste")
			(net "SMB_SCM_2_R2_SDA")
		)
		(pad "2" smd circle
			(at 0.40005 0 270)
			(size 0 0)
			(layers "F.Cu" "F.Mask" "F.Paste")
			(net "PVDD11_S3_P1_PMSDA_R")
		)
	)
	(footprint ""
		(layer "F.Cu")
		(at 27.7368 -421.069008)
		(property "Reference" "C6005"
			(at 0 0 0)
			(layer "F.SilkS")
			(hide yes)
			(effects
				(font
					(size 1.27 1.27)
				)
			)
		)
		(property "Value" ""
			(at 0 0 0)
			(layer "F.Fab")
			(effects
				(font
					(size 1.27 1.27)
				)
			)
		)
		(duplicate_pad_numbers_are_jumpers no)
		(fp_line
			(start -0.7874 -0.4064)
			(end -0.3556 -0.4064)
			(stroke
				(width 0.1524)
				(type default)
			)
			(layer "F.SilkS")
		)
		(fp_line
			(start 0.7874 -0.215392)
			(end 0.7874 0.4064)
			(stroke
				(width 0.1524)
				(type default)
			)
			(layer "F.SilkS")
		)
		(fp_line
			(start 0.7874 0.4064)
			(end -0.7874 0.4064)
			(stroke
				(width 0.1524)
				(type default)
			)
			(layer "F.SilkS")
		)
		(fp_line
			(start -0.6858 -0.3048)
			(end -0.1016 -0.3048)
			(stroke
				(width 0.1)
				(type default)
			)
			(layer "F.Fab")
		)
		(fp_line
			(start -0.6858 0.3048)
			(end -0.6858 -0.3048)
			(stroke
				(width 0.1)
				(type default)
			)
			(layer "F.Fab")
		)
		(fp_line
			(start -0.1016 -0.3048)
			(end -0.1016 -0.2794)
			(stroke
				(width 0.1)
				(type default)
			)
			(layer "F.Fab")
		)
		(fp_line
			(start -0.1016 -0.2794)
			(end 0.1016 -0.2794)
			(stroke
				(width 0.1)
				(type default)
			)
			(layer "F.Fab")
		)
		(fp_line
			(start -0.1016 0.2794)
			(end -0.1016 0.3048)
			(stroke
				(width 0.1)
				(type default)
			)
			(layer "F.Fab")
		)
		(fp_line
			(start -0.1016 0.3048)
			(end -0.6858 0.3048)
			(stroke
				(width 0.1)
				(type default)
			)
			(layer "F.Fab")
		)
		(fp_line
			(start 0.1016 -0.3048)
			(end 0.6858 -0.3048)
			(stroke
				(width 0.1)
				(type default)
			)
			(layer "F.Fab")
		)
		(fp_line
			(start 0.1016 -0.2794)
			(end 0.1016 -0.3048)
			(stroke
				(width 0.1)
				(type default)
			)
			(layer "F.Fab")
		)
		(fp_line
			(start 0.1016 0.2794)
			(end -0.1016 0.2794)
			(stroke
				(width 0.1)
				(type default)
			)
			(layer "F.Fab")
		)
		(fp_line
			(start 0.1016 0.3048)
			(end 0.1016 0.2794)
			(stroke
				(width 0.1)
				(type default)
			)
			(layer "F.Fab")
		)
		(fp_line
			(start 0.6858 -0.3048)
			(end 0.6858 0.3048)
			(stroke
				(width 0.1)
				(type default)
			)
			(layer "F.Fab")
		)
		(fp_line
			(start 0.6858 0.3048)
			(end 0.1016 0.3048)
			(stroke
				(width 0.1)
				(type default)
			)
			(layer "F.Fab")
		)
		(pad "1" smd rect
			(at -0.40005 0 180)
			(size 0.4572 0.508)
			(layers "F.Cu" "F.Mask" "F.Paste")
			(net "P2E_MB_BMC_TX_BUF2_DP<0>")
		)
		(pad "2" smd rect
			(at 0.40005 0 180)
			(size 0.4572 0.508)
			(layers "F.Cu" "F.Mask" "F.Paste")
			(net "P2E_MB_BMC_TX_BUF_C_DP<0>")
		)
	)
)
